(kicad_pcb
	(version 20260206)
	(generator "pcbnew")
	(generator_version "10.0")
	(general
		(thickness 1.6)
		(legacy_teardrops no)
	)
	(paper "A4")
	(title_block
		(title "04192023_DAF0TMB3IC0_F0TG_MB_C_brd_V02_OCP.brd")
		(comment 1 "Grand Teton / footprint 4761 of 8354 (J18), pads 227-291 of 291")
	)
	(layers
		(0 "F.Cu" signal "TOP")
		(4 "In1.Cu" signal "GND")
		(6 "In2.Cu" signal "IN1")
		(8 "In3.Cu" signal "GND1")
		(10 "In4.Cu" signal "IN2")
		(12 "In5.Cu" signal "GND2")
		(14 "In6.Cu" signal "IN3")
		(16 "In7.Cu" signal "GND3")
		(18 "In8.Cu" signal "VCC")
		(20 "In9.Cu" signal "VCC1")
		(22 "In10.Cu" signal "GND4")
		(24 "In11.Cu" signal "IN4")
		(26 "In12.Cu" signal "GND5")
		(28 "In13.Cu" signal "IN5")
		(30 "In14.Cu" signal "GND6")
		(32 "In15.Cu" signal "IN6")
		(34 "In16.Cu" signal "GND7")
		(2 "B.Cu" signal "BOTTOM")
		(9 "F.Adhes" user "F.Adhesive")
		(11 "B.Adhes" user "B.Adhesive")
		(13 "F.Paste" user "Package Geometry/Pastemask Top")
		(15 "B.Paste" user "Package Geometry/Pastemask Bottom")
		(5 "F.SilkS" user "Ref Des/Silkscreen Top")
		(7 "B.SilkS" user "Ref Des/Silkscreen Bottom")
		(1 "F.Mask" user "Board Geometry/Soldermask Top")
		(3 "B.Mask" user "Board Geometry/Soldermask Bottom")
		(17 "Dwgs.User" user "User.Drawings")
		(19 "Cmts.User" user "User.Comments")
		(21 "Eco1.User" user "User.Eco1")
		(23 "Eco2.User" user "User.Eco2")
		(25 "Edge.Cuts" user "Board Geometry/Outline")
		(27 "Margin" user)
		(31 "F.CrtYd" user "Package Geometry/Place Bound Top")
		(29 "B.CrtYd" user "Package Geometry/Place Bound Bottom")
		(35 "F.Fab" user "Ref Des/Assembly Top")
		(33 "B.Fab" user "Ref Des/Assembly Bottom")
	)
	(footprint ""
		(layer "F.Cu")
		(at 429.506126 -255.560068 180)
		(property "Reference" "J18"
			(at 0.484632 -81.752948 0)
			(unlocked yes)
			(layer "F.SilkS")
			(effects
				(font
					(size 0.7874 0.5842)
					(thickness 0.1524)
				)
			)
		)
		(property "Value" ""
			(at 0 0 180)
			(layer "F.Fab")
			(effects
				(font
					(size 1.27 1.27)
				)
			)
		)
		(duplicate_pad_numbers_are_jumpers no)
		(pad "227" smd rect
			(at 2.050034 11.474958 90)
			(size 0.519938 1.4986)
			(layers "F.Cu" "F.Mask" "F.Paste")
			(net "M_I_CPU0_SB_PAR")
		)
		(pad "228" smd rect
			(at 2.050034 12.325096 90)
			(size 0.519938 1.4986)
			(layers "F.Cu" "F.Mask" "F.Paste")
			(net "GND")
		)
		(pad "229" smd rect
			(at 2.050034 13.17498 90)
			(size 0.519938 1.4986)
			(layers "F.Cu" "F.Mask" "F.Paste")
			(net "M_I_CPU0_SB_CS_N<1>")
		)
		(pad "230" smd rect
			(at 2.050034 14.025118 90)
			(size 0.519938 1.4986)
			(layers "F.Cu" "F.Mask" "F.Paste")
			(net "GND")
		)
		(pad "231" smd rect
			(at 2.050034 14.875002 90)
			(size 0.519938 1.4986)
			(layers "F.Cu" "F.Mask" "F.Paste")
			(net "Net_2366")
		)
		(pad "232" smd rect
			(at 2.050034 15.724886 90)
			(size 0.519938 1.4986)
			(layers "F.Cu" "F.Mask" "F.Paste")
			(net "Net_2367")
		)
		(pad "233" smd rect
			(at 2.050034 16.575024 90)
			(size 0.519938 1.4986)
			(layers "F.Cu" "F.Mask" "F.Paste")
			(net "GND")
		)
		(pad "234" smd rect
			(at 2.050034 17.424908 90)
			(size 0.519938 1.4986)
			(layers "F.Cu" "F.Mask" "F.Paste")
			(net "M_I_CPU0_SB_CB<6>")
		)
		(pad "235" smd rect
			(at 2.050034 18.275046 90)
			(size 0.519938 1.4986)
			(layers "F.Cu" "F.Mask" "F.Paste")
			(net "GND")
		)
		(pad "236" smd rect
			(at 2.050034 19.12493 90)
			(size 0.519938 1.4986)
			(layers "F.Cu" "F.Mask" "F.Paste")
			(net "M_I_CPU0_SB_CB<7>")
		)
		(pad "237" smd rect
			(at 2.050034 19.975068 90)
			(size 0.519938 1.4986)
			(layers "F.Cu" "F.Mask" "F.Paste")
			(net "GND")
		)
		(pad "238" smd rect
			(at 2.050034 20.824952 90)
			(size 0.519938 1.4986)
			(layers "F.Cu" "F.Mask" "F.Paste")
			(net "M_I_CPU0_SB_DQS_DN<4>")
		)
		(pad "239" smd rect
			(at 2.050034 21.67509 90)
			(size 0.519938 1.4986)
			(layers "F.Cu" "F.Mask" "F.Paste")
			(net "M_I_CPU0_SB_DQS_DP<4>")
		)
		(pad "240" smd rect
			(at 2.050034 22.524974 90)
			(size 0.519938 1.4986)
			(layers "F.Cu" "F.Mask" "F.Paste")
			(net "GND")
		)
		(pad "241" smd rect
			(at 2.050034 23.375112 90)
			(size 0.519938 1.4986)
			(layers "F.Cu" "F.Mask" "F.Paste")
			(net "M_I_CPU0_SB_CB<2>")
		)
		(pad "242" smd rect
			(at 2.050034 24.224996 90)
			(size 0.519938 1.4986)
			(layers "F.Cu" "F.Mask" "F.Paste")
			(net "GND")
		)
		(pad "243" smd rect
			(at 2.050034 25.07488 90)
			(size 0.519938 1.4986)
			(layers "F.Cu" "F.Mask" "F.Paste")
			(net "M_I_CPU0_SB_CB<3>")
		)
		(pad "244" smd rect
			(at 2.050034 25.925018 90)
			(size 0.519938 1.4986)
			(layers "F.Cu" "F.Mask" "F.Paste")
			(net "GND")
		)
		(pad "245" smd rect
			(at 2.050034 26.774902 90)
			(size 0.519938 1.4986)
			(layers "F.Cu" "F.Mask" "F.Paste")
			(net "M_I_CPU0_SB_DQ<2>")
		)
		(pad "246" smd rect
			(at 2.050034 27.62504 90)
			(size 0.519938 1.4986)
			(layers "F.Cu" "F.Mask" "F.Paste")
			(net "GND")
		)
		(pad "247" smd rect
			(at 2.050034 28.474924 90)
			(size 0.519938 1.4986)
			(layers "F.Cu" "F.Mask" "F.Paste")
			(net "M_I_CPU0_SB_DQ<3>")
		)
		(pad "248" smd rect
			(at 2.050034 29.325062 90)
			(size 0.519938 1.4986)
			(layers "F.Cu" "F.Mask" "F.Paste")
			(net "GND")
		)
		(pad "249" smd rect
			(at 2.050034 30.174946 90)
			(size 0.519938 1.4986)
			(layers "F.Cu" "F.Mask" "F.Paste")
			(net "M_I_CPU0_SB_DQS_DN<5>")
		)
		(pad "250" smd rect
			(at 2.050034 31.025084 90)
			(size 0.519938 1.4986)
			(layers "F.Cu" "F.Mask" "F.Paste")
			(net "M_I_CPU0_SB_DQS_DP<5>")
		)
		(pad "251" smd rect
			(at 2.050034 31.874968 90)
			(size 0.519938 1.4986)
			(layers "F.Cu" "F.Mask" "F.Paste")
			(net "GND")
		)
		(pad "252" smd rect
			(at 2.050034 32.725106 90)
			(size 0.519938 1.4986)
			(layers "F.Cu" "F.Mask" "F.Paste")
			(net "M_I_CPU0_SB_DQ<6>")
		)
		(pad "253" smd rect
			(at 2.050034 33.57499 90)
			(size 0.519938 1.4986)
			(layers "F.Cu" "F.Mask" "F.Paste")
			(net "GND")
		)
		(pad "254" smd rect
			(at 2.050034 34.425128 90)
			(size 0.519938 1.4986)
			(layers "F.Cu" "F.Mask" "F.Paste")
			(net "M_I_CPU0_SB_DQ<7>")
		)
		(pad "255" smd rect
			(at 2.050034 35.275012 90)
			(size 0.519938 1.4986)
			(layers "F.Cu" "F.Mask" "F.Paste")
			(net "GND")
		)
		(pad "256" smd rect
			(at 2.050034 36.124896 90)
			(size 0.519938 1.4986)
			(layers "F.Cu" "F.Mask" "F.Paste")
			(net "M_I_CPU0_SB_DQ<10>")
		)
		(pad "257" smd rect
			(at 2.050034 36.975034 90)
			(size 0.519938 1.4986)
			(layers "F.Cu" "F.Mask" "F.Paste")
			(net "GND")
		)
		(pad "258" smd rect
			(at 2.050034 37.824918 90)
			(size 0.519938 1.4986)
			(layers "F.Cu" "F.Mask" "F.Paste")
			(net "M_I_CPU0_SB_DQ<11>")
		)
		(pad "259" smd rect
			(at 2.050034 38.675056 90)
			(size 0.519938 1.4986)
			(layers "F.Cu" "F.Mask" "F.Paste")
			(net "GND")
		)
		(pad "260" smd rect
			(at 2.050034 39.52494 90)
			(size 0.519938 1.4986)
			(layers "F.Cu" "F.Mask" "F.Paste")
			(net "M_I_CPU0_SB_DQS_DN<6>")
		)
		(pad "261" smd rect
			(at 2.050034 40.375078 90)
			(size 0.519938 1.4986)
			(layers "F.Cu" "F.Mask" "F.Paste")
			(net "M_I_CPU0_SB_DQS_DP<6>")
		)
		(pad "262" smd rect
			(at 2.050034 41.224962 90)
			(size 0.519938 1.4986)
			(layers "F.Cu" "F.Mask" "F.Paste")
			(net "GND")
		)
		(pad "263" smd rect
			(at 2.050034 42.0751 90)
			(size 0.519938 1.4986)
			(layers "F.Cu" "F.Mask" "F.Paste")
			(net "M_I_CPU0_SB_DQ<14>")
		)
		(pad "264" smd rect
			(at 2.050034 42.924984 90)
			(size 0.519938 1.4986)
			(layers "F.Cu" "F.Mask" "F.Paste")
			(net "GND")
		)
		(pad "265" smd rect
			(at 2.050034 43.775122 90)
			(size 0.519938 1.4986)
			(layers "F.Cu" "F.Mask" "F.Paste")
			(net "M_I_CPU0_SB_DQ<15>")
		)
		(pad "266" smd rect
			(at 2.050034 44.625006 90)
			(size 0.519938 1.4986)
			(layers "F.Cu" "F.Mask" "F.Paste")
			(net "GND")
		)
		(pad "267" smd rect
			(at 2.050034 45.47489 90)
			(size 0.519938 1.4986)
			(layers "F.Cu" "F.Mask" "F.Paste")
			(net "M_I_CPU0_SB_DQ<18>")
		)
		(pad "268" smd rect
			(at 2.050034 46.325028 90)
			(size 0.519938 1.4986)
			(layers "F.Cu" "F.Mask" "F.Paste")
			(net "GND")
		)
		(pad "269" smd rect
			(at 2.050034 47.174912 90)
			(size 0.519938 1.4986)
			(layers "F.Cu" "F.Mask" "F.Paste")
			(net "M_I_CPU0_SB_DQ<19>")
		)
		(pad "270" smd rect
			(at 2.050034 48.02505 90)
			(size 0.519938 1.4986)
			(layers "F.Cu" "F.Mask" "F.Paste")
			(net "GND")
		)
		(pad "271" smd rect
			(at 2.050034 48.874934 90)
			(size 0.519938 1.4986)
			(layers "F.Cu" "F.Mask" "F.Paste")
			(net "M_I_CPU0_SB_DQS_DN<7>")
		)
		(pad "272" smd rect
			(at 2.050034 49.725072 90)
			(size 0.519938 1.4986)
			(layers "F.Cu" "F.Mask" "F.Paste")
			(net "M_I_CPU0_SB_DQS_DP<7>")
		)
		(pad "273" smd rect
			(at 2.050034 50.574956 90)
			(size 0.519938 1.4986)
			(layers "F.Cu" "F.Mask" "F.Paste")
			(net "GND")
		)
		(pad "274" smd rect
			(at 2.050034 51.425094 90)
			(size 0.519938 1.4986)
			(layers "F.Cu" "F.Mask" "F.Paste")
			(net "M_I_CPU0_SB_DQ<22>")
		)
		(pad "275" smd rect
			(at 2.050034 52.274978 90)
			(size 0.519938 1.4986)
			(layers "F.Cu" "F.Mask" "F.Paste")
			(net "GND")
		)
		(pad "276" smd rect
			(at 2.050034 53.125116 90)
			(size 0.519938 1.4986)
			(layers "F.Cu" "F.Mask" "F.Paste")
			(net "M_I_CPU0_SB_DQ<23>")
		)
		(pad "277" smd rect
			(at 2.050034 53.975 90)
			(size 0.519938 1.4986)
			(layers "F.Cu" "F.Mask" "F.Paste")
			(net "GND")
		)
		(pad "278" smd rect
			(at 2.050034 54.824884 90)
			(size 0.519938 1.4986)
			(layers "F.Cu" "F.Mask" "F.Paste")
			(net "M_I_CPU0_SB_DQ<26>")
		)
		(pad "279" smd rect
			(at 2.050034 55.675022 90)
			(size 0.519938 1.4986)
			(layers "F.Cu" "F.Mask" "F.Paste")
			(net "GND")
		)
		(pad "280" smd rect
			(at 2.050034 56.524906 90)
			(size 0.519938 1.4986)
			(layers "F.Cu" "F.Mask" "F.Paste")
			(net "M_I_CPU0_SB_DQ<27>")
		)
		(pad "281" smd rect
			(at 2.050034 57.375044 90)
			(size 0.519938 1.4986)
			(layers "F.Cu" "F.Mask" "F.Paste")
			(net "GND")
		)
		(pad "282" smd rect
			(at 2.050034 58.224928 90)
			(size 0.519938 1.4986)
			(layers "F.Cu" "F.Mask" "F.Paste")
			(net "M_I_CPU0_SB_DQS_DN<8>")
		)
		(pad "283" smd rect
			(at 2.050034 59.075066 90)
			(size 0.519938 1.4986)
			(layers "F.Cu" "F.Mask" "F.Paste")
			(net "M_I_CPU0_SB_DQS_DP<8>")
		)
		(pad "284" smd rect
			(at 2.050034 59.92495 90)
			(size 0.519938 1.4986)
			(layers "F.Cu" "F.Mask" "F.Paste")
			(net "GND")
		)
		(pad "285" smd rect
			(at 2.050034 60.775088 90)
			(size 0.519938 1.4986)
			(layers "F.Cu" "F.Mask" "F.Paste")
			(net "M_I_CPU0_SB_DQ<30>")
		)
		(pad "286" smd rect
			(at 2.050034 61.624972 90)
			(size 0.519938 1.4986)
			(layers "F.Cu" "F.Mask" "F.Paste")
			(net "GND")
		)
		(pad "287" smd rect
			(at 2.050034 62.47511 90)
			(size 0.519938 1.4986)
			(layers "F.Cu" "F.Mask" "F.Paste")
			(net "M_I_CPU0_SB_DQ<31>")
		)
		(pad "288" smd rect
			(at 2.050034 63.324994 90)
			(size 0.519938 1.4986)
			(layers "F.Cu" "F.Mask" "F.Paste")
			(net "GND")
		)
		(pad "G1" thru_hole oval
			(at 0 -68.97497 90)
			(size 1.7272 3.4798)
			(drill oval 1.2192 2.4638)
			(layers "*.Cu" "*.Mask")
			(remove_unused_layers no)
			(net "GND")
			(clearance 0.127)
			(thermal_gap 0.127)
		)
		(pad "G2" thru_hole oval
			(at 0 3.875024 90)
			(size 1.7272 3.4798)
			(drill oval 1.2192 2.4638)
			(layers "*.Cu" "*.Mask")
			(remove_unused_layers no)
			(net "GND")
			(clearance 0.127)
			(thermal_gap 0.127)
		)
		(pad "G3" thru_hole oval
			(at 0 68.97497 90)
			(size 1.7272 3.4798)
			(drill oval 1.2192 2.4638)
			(layers "*.Cu" "*.Mask")
			(remove_unused_layers no)
			(net "GND")
			(clearance 0.127)
			(thermal_gap 0.127)
		)
	)
)
